# SCM (Grand Teton) — schematic netlist excerpt (pin names and nets, part order shuffled) for the footprints in the layout excerpt that follows; sources: Cadence DE-HDL packaged netlist, KiCad conversion of 12092022_DA0F0TMDCD0_F0T_Management_Board_D_brd_V3_OCP.brd

R552  Q_RES  33.2 1% CHIP  pkg 0402LF  page 21 : A = SPI_BMC_IO1_FLASH_R ; B = SPI_BMC_BOOT_MISO
R490  Q_RES  4.7K 1% CHIP  pkg 0402LF  page 45 : A = P3V3_AUX ; B = SPI_PCH_CS0_FLASH_R1_N

(kicad_pcb
	(version 20260206)
	(generator "pcbnew")
	(generator_version "10.0")
	(general
		(thickness 1.6)
		(legacy_teardrops no)
	)
	(paper "A4")
	(title_block
		(title "12092022_DA0F0TMDCD0_F0T_Management_Board_D_brd_V3_OCP.brd")
		(comment 1 "Grand Teton / footprints 5-6 of 1440")
	)
	(layers
		(0 "F.Cu" signal "TOP")
		(4 "In1.Cu" signal "GND")
		(6 "In2.Cu" signal "IN1")
		(8 "In3.Cu" signal "GND1")
		(10 "In4.Cu" signal "IN2")
		(12 "In5.Cu" signal "VCC")
		(14 "In6.Cu" signal "VCC1")
		(16 "In7.Cu" signal "IN3")
		(18 "In8.Cu" signal "GND2")
		(20 "In9.Cu" signal "IN4")
		(22 "In10.Cu" signal "GND3")
		(2 "B.Cu" signal "BOTTOM")
		(9 "F.Adhes" user "F.Adhesive")
		(11 "B.Adhes" user "B.Adhesive")
		(13 "F.Paste" user "Package Geometry/Pastemask Top")
		(15 "B.Paste" user "Package Geometry/Pastemask Bottom")
		(5 "F.SilkS" user "Ref Des/Silkscreen Top")
		(7 "B.SilkS" user "Ref Des/Silkscreen Bottom")
		(1 "F.Mask" user "Board Geometry/Soldermask Top")
		(3 "B.Mask" user "Board Geometry/Soldermask Bottom")
		(17 "Dwgs.User" user "User.Drawings")
		(19 "Cmts.User" user "User.Comments")
		(21 "Eco1.User" user "User.Eco1")
		(23 "Eco2.User" user "User.Eco2")
		(25 "Edge.Cuts" user "Board Geometry/Outline")
		(27 "Margin" user)
		(31 "F.CrtYd" user "Package Geometry/Place Bound Top")
		(29 "B.CrtYd" user "Package Geometry/Place Bound Bottom")
		(35 "F.Fab" user "Ref Des/Assembly Top")
		(33 "B.Fab" user "Ref Des/Assembly Bottom")
	)
	(footprint ""
		(layer "F.Cu")
		(at 42.932604 -87.679784 90)
		(property "Reference" "R490"
			(at 0 0 90)
			(layer "F.SilkS")
			(hide yes)
			(effects
				(font
					(size 1.27 1.27)
				)
			)
		)
		(property "Value" ""
			(at 0 0 90)
			(layer "F.Fab")
			(effects
				(font
					(size 1.27 1.27)
				)
			)
		)
		(duplicate_pad_numbers_are_jumpers no)
		(fp_line
			(start 0.7874 -0.4064)
			(end 0.7874 0.4064)
			(stroke
				(width 0.1524)
				(type default)
			)
			(layer "F.SilkS")
		)
		(fp_line
			(start -0.7874 -0.4064)
			(end 0.7874 -0.4064)
			(stroke
				(width 0.1524)
				(type default)
			)
			(layer "F.SilkS")
		)
		(fp_line
			(start 0.7874 0.4064)
			(end -0.7874 0.4064)
			(stroke
				(width 0.1524)
				(type default)
			)
			(layer "F.SilkS")
		)
		(fp_line
			(start -0.7874 0.4064)
			(end -0.7874 -0.4064)
			(stroke
				(width 0.1524)
				(type default)
			)
			(layer "F.SilkS")
		)
		(fp_line
			(start -0.12065 -0.305054)
			(end -0.12065 -0.2794)
			(stroke
				(width 0.1)
				(type default)
			)
			(layer "F.Fab")
		)
		(fp_line
			(start -0.67945 -0.305054)
			(end -0.12065 -0.305054)
			(stroke
				(width 0.1)
				(type default)
			)
			(layer "F.Fab")
		)
		(fp_line
			(start 0.67945 -0.3048)
			(end 0.67945 0.3048)
			(stroke
				(width 0.1)
				(type default)
			)
			(layer "F.Fab")
		)
		(fp_line
			(start 0.12065 -0.3048)
			(end 0.67945 -0.3048)
			(stroke
				(width 0.1)
				(type default)
			)
			(layer "F.Fab")
		)
		(fp_line
			(start 0.12065 -0.2794)
			(end 0.12065 -0.3048)
			(stroke
				(width 0.1)
				(type default)
			)
			(layer "F.Fab")
		)
		(fp_line
			(start -0.12065 -0.2794)
			(end 0.12065 -0.2794)
			(stroke
				(width 0.1)
				(type default)
			)
			(layer "F.Fab")
		)
		(fp_line
			(start 0.120396 0.2794)
			(end -0.12065 0.2794)
			(stroke
				(width 0.1)
				(type default)
			)
			(layer "F.Fab")
		)
		(fp_line
			(start -0.12065 0.2794)
			(end -0.12065 0.3048)
			(stroke
				(width 0.1)
				(type default)
			)
			(layer "F.Fab")
		)
		(fp_line
			(start 0.67945 0.3048)
			(end 0.120396 0.3048)
			(stroke
				(width 0.1)
				(type default)
			)
			(layer "F.Fab")
		)
		(fp_line
			(start 0.120396 0.3048)
			(end 0.120396 0.2794)
			(stroke
				(width 0.1)
				(type default)
			)
			(layer "F.Fab")
		)
		(fp_line
			(start -0.12065 0.3048)
			(end -0.67945 0.3048)
			(stroke
				(width 0.1)
				(type default)
			)
			(layer "F.Fab")
		)
		(fp_line
			(start -0.67945 0.3048)
			(end -0.67945 -0.305054)
			(stroke
				(width 0.1)
				(type default)
			)
			(layer "F.Fab")
		)
		(pad "1" smd circle
			(at -0.40005 0 90)
			(size 0 0)
			(layers "F.Cu" "F.Mask" "F.Paste")
			(net "P3V3_AUX")
		)
		(pad "2" smd circle
			(at 0.40005 0 90)
			(size 0 0)
			(layers "F.Cu" "F.Mask" "F.Paste")
			(net "SPI_PCH_CS0_FLASH_R1_N")
		)
	)
	(footprint ""
		(layer "F.Cu")
		(at 39.8272 -75.438)
		(property "Reference" "R552"
			(at 0 0 0)
			(layer "F.SilkS")
			(hide yes)
			(effects
				(font
					(size 1.27 1.27)
				)
			)
		)
		(property "Value" ""
			(at 0 0 0)
			(layer "F.Fab")
			(effects
				(font
					(size 1.27 1.27)
				)
			)
		)
		(duplicate_pad_numbers_are_jumpers no)
		(fp_line
			(start -0.7874 -0.4064)
			(end 0.7874 -0.4064)
			(stroke
				(width 0.1524)
				(type default)
			)
			(layer "F.SilkS")
		)
		(fp_line
			(start -0.7874 0.4064)
			(end -0.7874 -0.4064)
			(stroke
				(width 0.1524)
				(type default)
			)
			(layer "F.SilkS")
		)
		(fp_line
			(start 0.7874 -0.4064)
			(end 0.7874 0.4064)
			(stroke
				(width 0.1524)
				(type default)
			)
			(layer "F.SilkS")
		)
		(fp_line
			(start 0.7874 0.4064)
			(end -0.7874 0.4064)
			(stroke
				(width 0.1524)
				(type default)
			)
			(layer "F.SilkS")
		)
		(fp_line
			(start -0.67945 -0.305054)
			(end -0.12065 -0.305054)
			(stroke
				(width 0.1)
				(type default)
			)
			(layer "F.Fab")
		)
		(fp_line
			(start -0.67945 0.3048)
			(end -0.67945 -0.305054)
			(stroke
				(width 0.1)
				(type default)
			)
			(layer "F.Fab")
		)
		(fp_line
			(start -0.12065 -0.305054)
			(end -0.12065 -0.2794)
			(stroke
				(width 0.1)
				(type default)
			)
			(layer "F.Fab")
		)
		(fp_line
			(start -0.12065 -0.2794)
			(end 0.12065 -0.2794)
			(stroke
				(width 0.1)
				(type default)
			)
			(layer "F.Fab")
		)
		(fp_line
			(start -0.12065 0.2794)
			(end -0.12065 0.3048)
			(stroke
				(width 0.1)
				(type default)
			)
			(layer "F.Fab")
		)
		(fp_line
			(start -0.12065 0.3048)
			(end -0.67945 0.3048)
			(stroke
				(width 0.1)
				(type default)
			)
			(layer "F.Fab")
		)
		(fp_line
			(start 0.120396 0.2794)
			(end -0.12065 0.2794)
			(stroke
				(width 0.1)
				(type default)
			)
			(layer "F.Fab")
		)
		(fp_line
			(start 0.120396 0.3048)
			(end 0.120396 0.2794)
			(stroke
				(width 0.1)
				(type default)
			)
			(layer "F.Fab")
		)
		(fp_line
			(start 0.12065 -0.3048)
			(end 0.67945 -0.3048)
			(stroke
				(width 0.1)
				(type default)
			)
			(layer "F.Fab")
		)
		(fp_line
			(start 0.12065 -0.2794)
			(end 0.12065 -0.3048)
			(stroke
				(width 0.1)
				(type default)
			)
			(layer "F.Fab")
		)
		(fp_line
			(start 0.67945 -0.3048)
			(end 0.67945 0.3048)
			(stroke
				(width 0.1)
				(type default)
			)
			(layer "F.Fab")
		)
		(fp_line
			(start 0.67945 0.3048)
			(end 0.120396 0.3048)
			(stroke
				(width 0.1)
				(type default)
			)
			(layer "F.Fab")
		)
		(pad "1" smd circle
			(at -0.40005 0)
			(size 0 0)
			(layers "F.Cu" "F.Mask" "F.Paste")
			(net "SPI_BMC_IO1_FLASH_R")
		)
		(pad "2" smd circle
			(at 0.40005 0)
			(size 0 0)
			(layers "F.Cu" "F.Mask" "F.Paste")
			(net "SPI_BMC_BOOT_MISO")
		)
	)
)
